# T6G (Grand Teton) — schematic netlist excerpt (pin names and nets, part order shuffled) for the footprints in the layout excerpt that follows; sources: Cadence DE-HDL packaged netlist, KiCad conversion of 04192023_DAF0TMB3IC0_F0TG_MB_C_brd_V02_OCP.brd

PC134_5  Q_CAP  0.1UF 25V 10% X7R  pkg 0402  page 203 : A = SW_P12V_AUX_PVDDCR_CPU1_P0_FLT ; B = GND

U278  74LVC1G08W57  74LVC1G08W5-7 IC  pkg SOT25-5_0-95_3X1-6  page 241
  A  = FM_GPU_HSC_EN
  B  = GPU_PRSNT_R
  GND  = GND
  Y  = FM_GPU_HSC_EN_BUF_R
  VCC  = P3V3_AUX

(kicad_pcb
	(version 20260206)
	(generator "pcbnew")
	(generator_version "10.0")
	(general
		(thickness 1.6)
		(legacy_teardrops no)
	)
	(paper "A4")
	(title_block
		(title "04192023_DAF0TMB3IC0_F0TG_MB_C_brd_V02_OCP.brd")
		(comment 1 "Grand Teton / footprints 1711-1713 of 8354")
	)
	(layers
		(0 "F.Cu" signal "TOP")
		(4 "In1.Cu" signal "GND")
		(6 "In2.Cu" signal "IN1")
		(8 "In3.Cu" signal "GND1")
		(10 "In4.Cu" signal "IN2")
		(12 "In5.Cu" signal "GND2")
		(14 "In6.Cu" signal "IN3")
		(16 "In7.Cu" signal "GND3")
		(18 "In8.Cu" signal "VCC")
		(20 "In9.Cu" signal "VCC1")
		(22 "In10.Cu" signal "GND4")
		(24 "In11.Cu" signal "IN4")
		(26 "In12.Cu" signal "GND5")
		(28 "In13.Cu" signal "IN5")
		(30 "In14.Cu" signal "GND6")
		(32 "In15.Cu" signal "IN6")
		(34 "In16.Cu" signal "GND7")
		(2 "B.Cu" signal "BOTTOM")
		(9 "F.Adhes" user "F.Adhesive")
		(11 "B.Adhes" user "B.Adhesive")
		(13 "F.Paste" user "Package Geometry/Pastemask Top")
		(15 "B.Paste" user "Package Geometry/Pastemask Bottom")
		(5 "F.SilkS" user "Ref Des/Silkscreen Top")
		(7 "B.SilkS" user "Ref Des/Silkscreen Bottom")
		(1 "F.Mask" user "Board Geometry/Soldermask Top")
		(3 "B.Mask" user "Board Geometry/Soldermask Bottom")
		(17 "Dwgs.User" user "User.Drawings")
		(19 "Cmts.User" user "User.Comments")
		(21 "Eco1.User" user "User.Eco1")
		(23 "Eco2.User" user "User.Eco2")
		(25 "Edge.Cuts" user "Board Geometry/Outline")
		(27 "Margin" user)
		(31 "F.CrtYd" user "Package Geometry/Place Bound Top")
		(29 "B.CrtYd" user "Package Geometry/Place Bound Bottom")
		(35 "F.Fab" user "Ref Des/Assembly Top")
		(33 "B.Fab" user "Ref Des/Assembly Bottom")
	)
	(footprint ""
		(layer "F.Cu")
		(at 192.47358 -418.155882 90)
		(property "Reference" "U278"
			(at -1.78562 -2.481834 90)
			(unlocked yes)
			(layer "F.SilkS")
			(effects
				(font
					(size 0.7874 0.5842)
					(thickness 0.1524)
				)
				(justify left)
			)
		)
		(property "Value" ""
			(at 0 0 90)
			(layer "F.Fab")
			(effects
				(font
					(size 1.27 1.27)
				)
			)
		)
		(duplicate_pad_numbers_are_jumpers no)
		(fp_line
			(start 1.733296 -1.549908)
			(end 0.660908 -1.549908)
			(stroke
				(width 0.1524)
				(type default)
			)
			(layer "F.SilkS")
		)
		(fp_line
			(start 0.660908 -1.549908)
			(end 0 -0.889)
			(stroke
				(width 0.1524)
				(type default)
			)
			(layer "F.SilkS")
		)
		(fp_line
			(start -0.660908 -1.549908)
			(end -1.733296 -1.549908)
			(stroke
				(width 0.1524)
				(type default)
			)
			(layer "F.SilkS")
		)
		(fp_line
			(start -1.733296 -1.549908)
			(end -1.733296 1.549908)
			(stroke
				(width 0.1524)
				(type default)
			)
			(layer "F.SilkS")
		)
		(fp_line
			(start 0 -0.889)
			(end -0.660908 -1.549908)
			(stroke
				(width 0.1524)
				(type default)
			)
			(layer "F.SilkS")
		)
		(fp_line
			(start 1.733296 1.549908)
			(end 1.733296 -1.549908)
			(stroke
				(width 0.1524)
				(type default)
			)
			(layer "F.SilkS")
		)
		(fp_line
			(start -1.733296 1.549908)
			(end 1.733296 1.549908)
			(stroke
				(width 0.1524)
				(type default)
			)
			(layer "F.SilkS")
		)
		(fp_poly
			(pts
				(xy -2.505202 -1.550416) (xy -2.166366 -1.92913) (xy -1.95707 -1.401064)
			)
			(stroke
				(width 0)
				(type default)
			)
			(fill yes)
			(layer "F.SilkS")
		)
		(fp_line
			(start 0.849884 -1.549908)
			(end -0.849884 -1.549908)
			(stroke
				(width 0.1)
				(type default)
			)
			(layer "F.Fab")
		)
		(fp_line
			(start -0.849884 -1.549908)
			(end -0.849884 1.549908)
			(stroke
				(width 0.1)
				(type default)
			)
			(layer "F.Fab")
		)
		(fp_line
			(start 0.849884 1.549908)
			(end 0.849884 -1.549908)
			(stroke
				(width 0.1)
				(type default)
			)
			(layer "F.Fab")
		)
		(fp_line
			(start -0.849884 1.549908)
			(end 0.849884 1.549908)
			(stroke
				(width 0.1)
				(type default)
			)
			(layer "F.Fab")
		)
		(fp_poly
			(pts
				(xy -2.4384 -1.20396) (xy -2.4384 -0.69596) (xy -1.9304 -0.94996)
			)
			(stroke
				(width 0)
				(type default)
			)
			(fill yes)
			(layer "F.Fab")
		)
		(pad "1" smd rect
			(at -1.199896 -0.94996)
			(size 0.5588 0.8128)
			(layers "F.Cu" "F.Mask" "F.Paste")
			(net "FM_GPU_HSC_EN")
		)
		(pad "2" smd rect
			(at -1.199896 0)
			(size 0.5588 0.8128)
			(layers "F.Cu" "F.Mask" "F.Paste")
			(net "GPU_PRSNT_R")
		)
		(pad "3" smd rect
			(at -1.199896 0.94996)
			(size 0.5588 0.8128)
			(layers "F.Cu" "F.Mask" "F.Paste")
			(net "GND")
		)
		(pad "4" smd rect
			(at 1.199896 0.94996)
			(size 0.5588 0.8128)
			(layers "F.Cu" "F.Mask" "F.Paste")
			(net "FM_GPU_HSC_EN_BUF_R")
		)
		(pad "5" smd rect
			(at 1.199896 -0.94996)
			(size 0.5588 0.8128)
			(layers "F.Cu" "F.Mask" "F.Paste")
			(net "P3V3_AUX")
		)
	)
	(footprint ""
		(layer "F.Cu")
		(at 65.48882 -68.890388)
		(property "Reference" "ME2"
			(at 0 0 0)
			(layer "F.SilkS")
			(hide yes)
			(effects
				(font
					(size 1.27 1.27)
				)
			)
		)
		(property "Value" ""
			(at 0 0 0)
			(layer "F.Fab")
			(effects
				(font
					(size 1.27 1.27)
				)
			)
		)
		(duplicate_pad_numbers_are_jumpers no)
		(fp_rect
			(start 0 0)
			(end 3.3401 -0.5842)
			(stroke
				(width 0)
				(type default)
			)
			(fill yes)
			(layer "F.SilkS")
		)
		(fp_rect
			(start 1.32715 -3.2512)
			(end 2.01295 -3.4417)
			(stroke
				(width 0)
				(type default)
			)
			(fill yes)
			(layer "F.SilkS")
		)
		(fp_poly
			(pts
				(xy -0.070612 -0.681228) (xy -0.197612 -0.820928) (xy 0.852678 -1.91262) (xy 0.728472 -3.29184)
				(xy -0.248412 -4.300728) (xy -0.184912 -4.478528) (xy -0.007112 -4.503928) (xy 0.684022 -3.785616)
				(xy 0.65659 -4.0894) (xy 0.97155 -4.3434) (xy 1.22555 -4.3561) (xy 1.46685 -4.4704) (xy 2.01295 -4.4704)
				(xy 2.15265 -4.4069) (xy 2.44475 -4.191) (xy 2.49555 -4.191) (xy 2.59715 -4.2926) (xy 2.80035 -4.2672)
				(xy 2.88925 -4.1656) (xy 2.88925 -4.029456) (xy 3.345688 -4.503928) (xy 3.523488 -4.478528) (xy 3.586988 -4.300728)
				(xy 2.88925 -3.58013) (xy 2.88925 -3.3147) (xy 2.82575 -3.2385) (xy 2.67335 -3.2385) (xy 2.521966 -1.875282)
				(xy 2.545842 -1.85039)
				(arc
					(start 2.55905 -1.8415)
					(mid 2.648099 -1.766068)
					(end 2.717292 -1.672082)
				)
				(xy 3.536188 -0.820928) (xy 3.409188 -0.681228) (xy 3.244088 -0.693928)
				(arc
					(start 2.737612 -1.216914)
					(mid 2.31728 -0.925553)
					(end 1.86055 -1.1557)
				)
				(xy 0.92075 -1.1557) (xy 0.888492 -1.51384) (xy 0.094488 -0.693928)
			)
			(stroke
				(width 0)
				(type default)
			)
			(fill yes)
			(layer "F.SilkS")
		)
	)
	(footprint ""
		(layer "F.Cu")
		(at 339.254084 -339.40877)
		(property "Reference" "PC134_5"
			(at 0 0 0)
			(layer "F.SilkS")
			(hide yes)
			(effects
				(font
					(size 1.27 1.27)
				)
			)
		)
		(property "Value" ""
			(at 0 0 0)
			(layer "F.Fab")
			(effects
				(font
					(size 1.27 1.27)
				)
			)
		)
		(duplicate_pad_numbers_are_jumpers no)
		(fp_line
			(start -0.7874 -0.4064)
			(end 0.7874 -0.4064)
			(stroke
				(width 0.1524)
				(type default)
			)
			(layer "F.SilkS")
		)
		(fp_line
			(start -0.7874 0.4064)
			(end -0.7874 -0.4064)
			(stroke
				(width 0.1524)
				(type default)
			)
			(layer "F.SilkS")
		)
		(fp_line
			(start 0.7874 -0.4064)
			(end 0.7874 0.4064)
			(stroke
				(width 0.1524)
				(type default)
			)
			(layer "F.SilkS")
		)
		(fp_line
			(start 0.7874 0.4064)
			(end -0.7874 0.4064)
			(stroke
				(width 0.1524)
				(type default)
			)
			(layer "F.SilkS")
		)
		(fp_line
			(start -0.67945 -0.305054)
			(end -0.12065 -0.305054)
			(stroke
				(width 0.1)
				(type default)
			)
			(layer "F.Fab")
		)
		(fp_line
			(start -0.67945 0.3048)
			(end -0.67945 -0.305054)
			(stroke
				(width 0.1)
				(type default)
			)
			(layer "F.Fab")
		)
		(fp_line
			(start -0.12065 -0.305054)
			(end -0.12065 -0.2794)
			(stroke
				(width 0.1)
				(type default)
			)
			(layer "F.Fab")
		)
		(fp_line
			(start -0.12065 -0.2794)
			(end 0.12065 -0.2794)
			(stroke
				(width 0.1)
				(type default)
			)
			(layer "F.Fab")
		)
		(fp_line
			(start -0.12065 0.2794)
			(end -0.12065 0.3048)
			(stroke
				(width 0.1)
				(type default)
			)
			(layer "F.Fab")
		)
		(fp_line
			(start -0.12065 0.3048)
			(end -0.67945 0.3048)
			(stroke
				(width 0.1)
				(type default)
			)
			(layer "F.Fab")
		)
		(fp_line
			(start 0.120396 0.2794)
			(end -0.12065 0.2794)
			(stroke
				(width 0.1)
				(type default)
			)
			(layer "F.Fab")
		)
		(fp_line
			(start 0.120396 0.3048)
			(end 0.120396 0.2794)
			(stroke
				(width 0.1)
				(type default)
			)
			(layer "F.Fab")
		)
		(fp_line
			(start 0.12065 -0.3048)
			(end 0.67945 -0.3048)
			(stroke
				(width 0.1)
				(type default)
			)
			(layer "F.Fab")
		)
		(fp_line
			(start 0.12065 -0.2794)
			(end 0.12065 -0.3048)
			(stroke
				(width 0.1)
				(type default)
			)
			(layer "F.Fab")
		)
		(fp_line
			(start 0.67945 -0.3048)
			(end 0.67945 0.3048)
			(stroke
				(width 0.1)
				(type default)
			)
			(layer "F.Fab")
		)
		(fp_line
			(start 0.67945 0.3048)
			(end 0.120396 0.3048)
			(stroke
				(width 0.1)
				(type default)
			)
			(layer "F.Fab")
		)
		(pad "1" smd circle
			(at -0.40005 0)
			(size 0 0)
			(layers "F.Cu" "F.Mask" "F.Paste")
			(net "SW_P12V_AUX_PVDDCR_CPU1_P0_FLT")
		)
		(pad "2" smd circle
			(at 0.40005 0)
			(size 0 0)
			(layers "F.Cu" "F.Mask" "F.Paste")
			(net "GND")
		)
	)
)
